(kicad_pcb
	(version 20260206)
	(generator "pcbnew")
	(generator_version "10.0")
	(general
		(thickness 1.6)
		(legacy_teardrops no)
	)
	(paper "A4")
	(title_block
		(title "v1-chassis-manager — T6M_CM_d_v01_1031_1645.brd")
		(comment 1 "Open CloudServer (Microsoft) / footprints 1408-1417 of 2512")
	)
	(layers
		(0 "F.Cu" signal "TOP")
		(4 "In1.Cu" signal "GND1")
		(6 "In2.Cu" signal "IN1")
		(8 "In3.Cu" signal "VCC1")
		(10 "In4.Cu" signal "VCC2")
		(12 "In5.Cu" signal "GND2")
		(14 "In6.Cu" signal "IN2")
		(16 "In7.Cu" signal "IN3")
		(18 "In8.Cu" signal "GND3")
		(2 "B.Cu" signal "BOTTOM")
		(9 "F.Adhes" user "F.Adhesive")
		(11 "B.Adhes" user "B.Adhesive")
		(13 "F.Paste" user "Package Geometry/Pastemask Top")
		(15 "B.Paste" user "Package Geometry/Pastemask Bottom")
		(5 "F.SilkS" user "Ref Des/Silkscreen Top")
		(7 "B.SilkS" user "Ref Des/Silkscreen Bottom")
		(1 "F.Mask" user "Board Geometry/Soldermask Top")
		(3 "B.Mask" user "Board Geometry/Soldermask Bottom")
		(17 "Dwgs.User" user "User.Drawings")
		(19 "Cmts.User" user "User.Comments")
		(21 "Eco1.User" user "User.Eco1")
		(23 "Eco2.User" user "User.Eco2")
		(25 "Edge.Cuts" user "Board Geometry/Outline")
		(27 "Margin" user)
		(31 "F.CrtYd" user "Package Geometry/Place Bound Top")
		(29 "B.CrtYd" user "Package Geometry/Place Bound Bottom")
		(35 "F.Fab" user "Ref Des/Assembly Top")
		(33 "B.Fab" user "Ref Des/Assembly Bottom")
	)
	(footprint ""
		(layer "F.Cu")
		(at 68.480686 -148.476462 90)
		(property "Reference" "R302"
			(at 1.233932 -0.013462 90)
			(unlocked yes)
			(layer "F.SilkS")
			(effects
				(font
					(size 0.7874 0.5842)
					(thickness 0.1524)
				)
				(justify left)
			)
		)
		(property "Value" ""
			(at 0 0 90)
			(layer "F.Fab")
			(effects
				(font
					(size 1.27 1.27)
				)
			)
		)
		(duplicate_pad_numbers_are_jumpers no)
		(fp_line
			(start 0.7874 -0.4064)
			(end 0.7874 0.4064)
			(stroke
				(width 0.1524)
				(type default)
			)
			(layer "F.SilkS")
		)
		(fp_line
			(start -0.7874 -0.4064)
			(end 0.7874 -0.4064)
			(stroke
				(width 0.1524)
				(type default)
			)
			(layer "F.SilkS")
		)
		(fp_line
			(start 0.7874 0.4064)
			(end -0.7874 0.4064)
			(stroke
				(width 0.1524)
				(type default)
			)
			(layer "F.SilkS")
		)
		(fp_line
			(start -0.7874 0.4064)
			(end -0.7874 -0.4064)
			(stroke
				(width 0.1524)
				(type default)
			)
			(layer "F.SilkS")
		)
		(fp_poly
			(pts
				(xy -0.508 0.2794) (xy -0.508 0.2286) (xy -0.635 0.2286) (xy -0.635 -0.254) (xy -0.5334 -0.254)
				(xy -0.5334 -0.2794) (xy 0.5334 -0.2794) (xy 0.5334 -0.254) (xy 0.635 -0.254) (xy 0.635 0.254) (xy 0.5334 0.254)
				(xy 0.5334 0.2794)
			)
			(stroke
				(width 0)
				(type default)
			)
			(fill no)
			(layer "F.CrtYd")
		)
		(pad "1" smd rect
			(at 0.40005 0 90)
			(size 0.4572 0.508)
			(layers "F.Cu" "F.Mask" "F.Paste")
			(net "P3V3_NODE1")
		)
		(pad "2" smd rect
			(at -0.40005 0 90)
			(size 0.4572 0.508)
			(layers "F.Cu" "F.Mask" "F.Paste")
			(net "BMC_NODE1_JTAG_TMS")
		)
	)
	(footprint ""
		(layer "F.Cu")
		(at 148.040852 -142.09903 180)
		(property "Reference" "R310"
			(at -1.563116 -1.17221 0)
			(unlocked yes)
			(layer "F.SilkS")
			(effects
				(font
					(size 0.635 0.4064)
					(thickness 0.1524)
				)
				(justify left)
			)
		)
		(property "Value" ""
			(at 0 0 180)
			(layer "F.Fab")
			(effects
				(font
					(size 1.27 1.27)
				)
			)
		)
		(duplicate_pad_numbers_are_jumpers no)
		(fp_line
			(start 0.7874 0.4064)
			(end -0.7874 0.4064)
			(stroke
				(width 0.1524)
				(type default)
			)
			(layer "F.SilkS")
		)
		(fp_line
			(start 0.7874 -0.4064)
			(end 0.7874 0.4064)
			(stroke
				(width 0.1524)
				(type default)
			)
			(layer "F.SilkS")
		)
		(fp_line
			(start -0.7874 0.4064)
			(end -0.7874 -0.4064)
			(stroke
				(width 0.1524)
				(type default)
			)
			(layer "F.SilkS")
		)
		(fp_line
			(start -0.7874 -0.4064)
			(end 0.7874 -0.4064)
			(stroke
				(width 0.1524)
				(type default)
			)
			(layer "F.SilkS")
		)
		(fp_poly
			(pts
				(xy -0.508 0.2794) (xy -0.508 0.2286) (xy -0.635 0.2286) (xy -0.635 -0.254) (xy -0.5334 -0.254)
				(xy -0.5334 -0.2794) (xy 0.5334 -0.2794) (xy 0.5334 -0.254) (xy 0.635 -0.254) (xy 0.635 0.254) (xy 0.5334 0.254)
				(xy 0.5334 0.2794)
			)
			(stroke
				(width 0)
				(type default)
			)
			(fill no)
			(layer "F.CrtYd")
		)
		(pad "1" smd rect
			(at 0.40005 0 180)
			(size 0.4572 0.508)
			(layers "F.Cu" "F.Mask" "F.Paste")
			(net "PCIE_SW_I2C_SDA")
		)
		(pad "2" smd rect
			(at -0.40005 0 180)
			(size 0.4572 0.508)
			(layers "F.Cu" "F.Mask" "F.Paste")
			(net "P3V3_NODE1")
		)
	)
	(footprint ""
		(layer "F.Cu")
		(at 152.67051 -148.057362)
		(property "Reference" "C527"
			(at -1.33858 -3.798824 0)
			(unlocked yes)
			(layer "F.SilkS")
			(effects
				(font
					(size 0.635 0.4064)
					(thickness 0.1524)
				)
				(justify left)
			)
		)
		(property "Value" ""
			(at 0 0 0)
			(layer "F.Fab")
			(effects
				(font
					(size 1.27 1.27)
				)
			)
		)
		(duplicate_pad_numbers_are_jumpers no)
		(fp_line
			(start -0.7874 -0.4064)
			(end 0.7874 -0.4064)
			(stroke
				(width 0.1524)
				(type default)
			)
			(layer "F.SilkS")
		)
		(fp_line
			(start -0.7874 0.4064)
			(end -0.7874 -0.4064)
			(stroke
				(width 0.1524)
				(type default)
			)
			(layer "F.SilkS")
		)
		(fp_line
			(start 0 0.381)
			(end 0 -0.381)
			(stroke
				(width 0.1524)
				(type default)
			)
			(layer "F.SilkS")
		)
		(fp_line
			(start 0.7874 -0.4064)
			(end 0.7874 0.4064)
			(stroke
				(width 0.1524)
				(type default)
			)
			(layer "F.SilkS")
		)
		(fp_line
			(start 0.7874 0.4064)
			(end -0.7874 0.4064)
			(stroke
				(width 0.1524)
				(type default)
			)
			(layer "F.SilkS")
		)
		(fp_poly
			(pts
				(xy -0.5334 0.254) (xy -0.635 0.254) (xy -0.635 0.2286) (xy -0.635 -0.254) (xy -0.5334 -0.254) (xy -0.5334 -0.2794)
				(xy 0.5334 -0.2794) (xy 0.5334 -0.254) (xy 0.635 -0.254) (xy 0.635 0.254) (xy 0.5334 0.254) (xy 0.5334 0.2794)
				(xy -0.508 0.2794) (xy -0.5334 0.2794)
			)
			(stroke
				(width 0)
				(type default)
			)
			(fill no)
			(layer "F.CrtYd")
		)
		(pad "1" smd rect
			(at 0.40005 0)
			(size 0.4572 0.508)
			(layers "F.Cu" "F.Mask" "F.Paste")
			(net "LAN2_LED_ACT_N")
		)
		(pad "2" smd rect
			(at -0.40005 0)
			(size 0.4572 0.508)
			(layers "F.Cu" "F.Mask" "F.Paste")
			(net "GND")
		)
	)
	(footprint ""
		(layer "F.Cu")
		(at 53.621686 -120.942862 180)
		(property "Reference" "L13"
			(at 5.542026 0.271526 0)
			(unlocked yes)
			(layer "F.SilkS")
			(effects
				(font
					(size 0.7874 0.5842)
					(thickness 0.1524)
				)
			)
		)
		(property "Value" ""
			(at 0 0 180)
			(layer "F.Fab")
			(effects
				(font
					(size 1.27 1.27)
				)
			)
		)
		(duplicate_pad_numbers_are_jumpers no)
		(fp_line
			(start 1.2954 0.635)
			(end -1.2954 0.635)
			(stroke
				(width 0.1524)
				(type default)
			)
			(layer "F.SilkS")
		)
		(fp_line
			(start 1.2954 -0.635)
			(end 1.2954 0.635)
			(stroke
				(width 0.1524)
				(type default)
			)
			(layer "F.SilkS")
		)
		(fp_line
			(start 0.127 -0.5842)
			(end 0.127 0.5842)
			(stroke
				(width 0.1524)
				(type default)
			)
			(layer "F.SilkS")
		)
		(fp_line
			(start -0.127 -0.5842)
			(end -0.127 0.5842)
			(stroke
				(width 0.1524)
				(type default)
			)
			(layer "F.SilkS")
		)
		(fp_line
			(start -1.2954 -0.635)
			(end 1.2954 -0.635)
			(stroke
				(width 0.1524)
				(type default)
			)
			(layer "F.SilkS")
		)
		(fp_line
			(start -1.2954 -0.635)
			(end -1.2954 0.635)
			(stroke
				(width 0.1524)
				(type default)
			)
			(layer "F.SilkS")
		)
		(fp_poly
			(pts
				(xy -0.9144 0.508) (xy -0.9144 0.3556) (xy -1.143 0.3556) (xy -1.143 -0.3556) (xy -0.9144 -0.3556)
				(xy -0.9144 -0.508) (xy 0.9144 -0.508) (xy 0.9144 -0.3556) (xy 1.143 -0.3556) (xy 1.143 0.3556)
				(xy 0.9144 0.3556) (xy 0.9144 0.508)
			)
			(stroke
				(width 0)
				(type default)
			)
			(fill no)
			(layer "F.CrtYd")
		)
		(pad "1" smd rect
			(at 0.7366 0 270)
			(size 0.7112 0.8128)
			(layers "F.Cu" "F.Mask" "F.Paste")
			(net "BMC_NODE1_OSC1_VDD")
		)
		(pad "2" smd rect
			(at -0.7366 0 270)
			(size 0.7112 0.8128)
			(layers "F.Cu" "F.Mask" "F.Paste")
			(net "P3V3_NODE1")
		)
	)
	(footprint ""
		(layer "F.Cu")
		(at 98.06305 -181.722268)
		(property "Reference" "R146"
			(at 84.126324 75.315826 0)
			(unlocked yes)
			(layer "F.SilkS")
			(effects
				(font
					(size 0.7874 0.5842)
					(thickness 0.1524)
				)
				(justify left)
			)
		)
		(property "Value" ""
			(at 0 0 0)
			(layer "F.Fab")
			(effects
				(font
					(size 1.27 1.27)
				)
			)
		)
		(duplicate_pad_numbers_are_jumpers no)
		(fp_line
			(start -0.7874 -0.4064)
			(end 0.7874 -0.4064)
			(stroke
				(width 0.1524)
				(type default)
			)
			(layer "F.SilkS")
		)
		(fp_line
			(start -0.7874 0.4064)
			(end -0.7874 -0.4064)
			(stroke
				(width 0.1524)
				(type default)
			)
			(layer "F.SilkS")
		)
		(fp_line
			(start 0.7874 -0.4064)
			(end 0.7874 0.4064)
			(stroke
				(width 0.1524)
				(type default)
			)
			(layer "F.SilkS")
		)
		(fp_line
			(start 0.7874 0.4064)
			(end -0.7874 0.4064)
			(stroke
				(width 0.1524)
				(type default)
			)
			(layer "F.SilkS")
		)
		(fp_poly
			(pts
				(xy -0.508 0.2794) (xy -0.508 0.2286) (xy -0.635 0.2286) (xy -0.635 -0.254) (xy -0.5334 -0.254)
				(xy -0.5334 -0.2794) (xy 0.5334 -0.2794) (xy 0.5334 -0.254) (xy 0.635 -0.254) (xy 0.635 0.254) (xy 0.5334 0.254)
				(xy 0.5334 0.2794)
			)
			(stroke
				(width 0)
				(type default)
			)
			(fill no)
			(layer "F.CrtYd")
		)
		(pad "1" smd rect
			(at 0.40005 0)
			(size 0.4572 0.508)
			(layers "F.Cu" "F.Mask" "F.Paste")
			(net "ATTENTION_LED_N")
		)
		(pad "2" smd rect
			(at -0.40005 0)
			(size 0.4572 0.508)
			(layers "F.Cu" "F.Mask" "F.Paste")
			(net "P3V3_NODE1")
		)
	)
	(footprint ""
		(layer "F.Cu")
		(at 130.902456 -161.150046 180)
		(property "Reference" "R775"
			(at 61.040772 -108.866686 0)
			(unlocked yes)
			(layer "F.SilkS")
			(effects
				(font
					(size 0.7874 0.5842)
					(thickness 0.1524)
				)
				(justify left)
			)
		)
		(property "Value" ""
			(at 0 0 180)
			(layer "F.Fab")
			(effects
				(font
					(size 1.27 1.27)
				)
			)
		)
		(duplicate_pad_numbers_are_jumpers no)
		(fp_line
			(start 0.7874 0.4064)
			(end -0.7874 0.4064)
			(stroke
				(width 0.1524)
				(type default)
			)
			(layer "F.SilkS")
		)
		(fp_line
			(start 0.7874 -0.4064)
			(end 0.7874 0.4064)
			(stroke
				(width 0.1524)
				(type default)
			)
			(layer "F.SilkS")
		)
		(fp_line
			(start -0.7874 0.4064)
			(end -0.7874 -0.4064)
			(stroke
				(width 0.1524)
				(type default)
			)
			(layer "F.SilkS")
		)
		(fp_line
			(start -0.7874 -0.4064)
			(end 0.7874 -0.4064)
			(stroke
				(width 0.1524)
				(type default)
			)
			(layer "F.SilkS")
		)
		(fp_poly
			(pts
				(xy -0.508 0.2794) (xy -0.508 0.2286) (xy -0.635 0.2286) (xy -0.635 -0.254) (xy -0.5334 -0.254)
				(xy -0.5334 -0.2794) (xy 0.5334 -0.2794) (xy 0.5334 -0.254) (xy 0.635 -0.254) (xy 0.635 0.254) (xy 0.5334 0.254)
				(xy 0.5334 0.2794)
			)
			(stroke
				(width 0)
				(type default)
			)
			(fill no)
			(layer "F.CrtYd")
		)
		(pad "1" smd rect
			(at 0.40005 0 180)
			(size 0.4572 0.508)
			(layers "F.Cu" "F.Mask" "F.Paste")
			(net "CPLD123_RSV3")
		)
		(pad "2" smd rect
			(at -0.40005 0 180)
			(size 0.4572 0.508)
			(layers "F.Cu" "F.Mask" "F.Paste")
			(net "CPLD3_RSV3")
		)
	)
	(footprint ""
		(layer "F.Cu")
		(at 53.561996 -160.014158 180)
		(property "Reference" "C517"
			(at 0.575564 5.472176 0)
			(unlocked yes)
			(layer "F.SilkS")
			(effects
				(font
					(size 0.7874 0.5842)
					(thickness 0.1524)
				)
				(justify left)
			)
		)
		(property "Value" ""
			(at 0 0 180)
			(layer "F.Fab")
			(effects
				(font
					(size 1.27 1.27)
				)
			)
		)
		(duplicate_pad_numbers_are_jumpers no)
		(fp_line
			(start 0.7874 0.4064)
			(end -0.7874 0.4064)
			(stroke
				(width 0.1524)
				(type default)
			)
			(layer "F.SilkS")
		)
		(fp_line
			(start 0.7874 -0.4064)
			(end 0.7874 0.4064)
			(stroke
				(width 0.1524)
				(type default)
			)
			(layer "F.SilkS")
		)
		(fp_line
			(start 0 0.381)
			(end 0 -0.381)
			(stroke
				(width 0.1524)
				(type default)
			)
			(layer "F.SilkS")
		)
		(fp_line
			(start -0.7874 0.4064)
			(end -0.7874 -0.4064)
			(stroke
				(width 0.1524)
				(type default)
			)
			(layer "F.SilkS")
		)
		(fp_line
			(start -0.7874 -0.4064)
			(end 0.7874 -0.4064)
			(stroke
				(width 0.1524)
				(type default)
			)
			(layer "F.SilkS")
		)
		(fp_poly
			(pts
				(xy -0.5334 0.254) (xy -0.635 0.254) (xy -0.635 0.2286) (xy -0.635 -0.254) (xy -0.5334 -0.254) (xy -0.5334 -0.2794)
				(xy 0.5334 -0.2794) (xy 0.5334 -0.254) (xy 0.635 -0.254) (xy 0.635 0.254) (xy 0.5334 0.254) (xy 0.5334 0.2794)
				(xy -0.508 0.2794) (xy -0.5334 0.2794)
			)
			(stroke
				(width 0)
				(type default)
			)
			(fill no)
			(layer "F.CrtYd")
		)
		(pad "1" smd rect
			(at 0.40005 0 180)
			(size 0.4572 0.508)
			(layers "F.Cu" "F.Mask" "F.Paste")
			(net "LAN1_LED_ACT_N")
		)
		(pad "2" smd rect
			(at -0.40005 0 180)
			(size 0.4572 0.508)
			(layers "F.Cu" "F.Mask" "F.Paste")
			(net "GND")
		)
	)
	(footprint ""
		(layer "F.Cu")
		(at 53.561996 -158.998158)
		(property "Reference" "R558"
			(at -0.575564 -5.39115 0)
			(unlocked yes)
			(layer "F.SilkS")
			(effects
				(font
					(size 0.7874 0.5842)
					(thickness 0.1524)
				)
				(justify left)
			)
		)
		(property "Value" ""
			(at 0 0 0)
			(layer "F.Fab")
			(effects
				(font
					(size 1.27 1.27)
				)
			)
		)
		(duplicate_pad_numbers_are_jumpers no)
		(fp_line
			(start -0.7874 -0.4064)
			(end 0.7874 -0.4064)
			(stroke
				(width 0.1524)
				(type default)
			)
			(layer "F.SilkS")
		)
		(fp_line
			(start -0.7874 0.4064)
			(end -0.7874 -0.4064)
			(stroke
				(width 0.1524)
				(type default)
			)
			(layer "F.SilkS")
		)
		(fp_line
			(start 0.7874 -0.4064)
			(end 0.7874 0.4064)
			(stroke
				(width 0.1524)
				(type default)
			)
			(layer "F.SilkS")
		)
		(fp_line
			(start 0.7874 0.4064)
			(end -0.7874 0.4064)
			(stroke
				(width 0.1524)
				(type default)
			)
			(layer "F.SilkS")
		)
		(fp_poly
			(pts
				(xy -0.508 0.2794) (xy -0.508 0.2286) (xy -0.635 0.2286) (xy -0.635 -0.254) (xy -0.5334 -0.254)
				(xy -0.5334 -0.2794) (xy 0.5334 -0.2794) (xy 0.5334 -0.254) (xy 0.635 -0.254) (xy 0.635 0.254) (xy 0.5334 0.254)
				(xy 0.5334 0.2794)
			)
			(stroke
				(width 0)
				(type default)
			)
			(fill no)
			(layer "F.CrtYd")
		)
		(pad "1" smd rect
			(at 0.40005 0)
			(size 0.4572 0.508)
			(layers "F.Cu" "F.Mask" "F.Paste")
			(net "GND")
		)
		(pad "2" smd rect
			(at -0.40005 0)
			(size 0.4572 0.508)
			(layers "F.Cu" "F.Mask" "F.Paste")
			(net "LAN1_TEST_EN")
		)
	)
	(footprint ""
		(layer "F.Cu")
		(at 44.454826 -169.625264 -90)
		(property "Reference" "U114"
			(at 0.081788 3.65506 90)
			(unlocked yes)
			(layer "F.SilkS")
			(effects
				(font
					(size 0.7874 0.5842)
					(thickness 0.1524)
				)
			)
		)
		(property "Value" ""
			(at 0 0 270)
			(layer "F.Fab")
			(effects
				(font
					(size 1.27 1.27)
				)
			)
		)
		(duplicate_pad_numbers_are_jumpers no)
		(fp_line
			(start -1.651 1.905)
			(end -1.651 -1.905)
			(stroke
				(width 0.1524)
				(type default)
			)
			(layer "F.SilkS")
		)
		(fp_line
			(start 1.651 1.905)
			(end -1.651 1.905)
			(stroke
				(width 0.1524)
				(type default)
			)
			(layer "F.SilkS")
		)
		(fp_line
			(start -1.651 -1.905)
			(end 1.651 -1.905)
			(stroke
				(width 0.1524)
				(type default)
			)
			(layer "F.SilkS")
		)
		(fp_line
			(start 1.651 -1.905)
			(end 1.651 1.905)
			(stroke
				(width 0.1524)
				(type default)
			)
			(layer "F.SilkS")
		)
		(fp_poly
			(pts
				(xy -1.524 0.7112) (xy -1.524 1.7526) (xy -0.508 1.7526) (xy -0.508 0.6985) (xy 0.508 0.6985) (xy 0.508 1.7526)
				(xy 1.524 1.7526) (xy 1.524 0.6985) (xy 1.524 -0.6985) (xy 0.508 -0.6985) (xy 0.508 -1.7526) (xy -0.508 -1.7526)
				(xy -0.508 -0.6985) (xy -1.524 -0.6985) (xy -1.524 0.6985)
			)
			(stroke
				(width 0)
				(type default)
			)
			(fill no)
			(layer "F.CrtYd")
		)
		(fp_text user "G"
			(at -1.410208 2.63779 0)
			(unlocked yes)
			(layer "F.SilkS")
			(effects
				(font
					(size 0.635 0.4064)
					(thickness 0.1524)
				)
			)
		)
		(fp_text user "S"
			(at 1.344168 2.23647 0)
			(unlocked yes)
			(layer "F.SilkS")
			(effects
				(font
					(size 0.635 0.4064)
					(thickness 0.1524)
				)
			)
		)
		(fp_text user "D"
			(at -0.016764 -2.367534 0)
			(unlocked yes)
			(layer "F.SilkS")
			(effects
				(font
					(size 0.635 0.4064)
					(thickness 0.1524)
				)
			)
		)
		(pad "D" smd rect
			(at 0 -1.1176 270)
			(size 1.016 1.27)
			(layers "F.Cu" "F.Mask" "F.Paste")
			(net "PSU_DC_OK_N")
		)
		(pad "G" smd rect
			(at -1.016 1.1176 270)
			(size 1.016 1.27)
			(layers "F.Cu" "F.Mask" "F.Paste")
			(net "N53103066")
		)
		(pad "S" smd rect
			(at 1.016 1.1176 270)
			(size 1.016 1.27)
			(layers "F.Cu" "F.Mask" "F.Paste")
			(net "GND")
		)
	)
	(footprint ""
		(layer "F.Cu")
		(at 19.651472 -74.207878 90)
		(property "Reference" "L38"
			(at 3.237738 -0.04318 90)
			(unlocked yes)
			(layer "F.SilkS")
			(effects
				(font
					(size 0.7874 0.5842)
					(thickness 0.1524)
				)
			)
		)
		(property "Value" ""
			(at 0 0 90)
			(layer "F.Fab")
			(effects
				(font
					(size 1.27 1.27)
				)
			)
		)
		(duplicate_pad_numbers_are_jumpers no)
		(fp_line
			(start 1.2954 -0.635)
			(end 1.2954 0.635)
			(stroke
				(width 0.1524)
				(type default)
			)
			(layer "F.SilkS")
		)
		(fp_line
			(start -1.2954 -0.635)
			(end 1.2954 -0.635)
			(stroke
				(width 0.1524)
				(type default)
			)
			(layer "F.SilkS")
		)
		(fp_line
			(start -1.2954 -0.635)
			(end -1.2954 0.635)
			(stroke
				(width 0.1524)
				(type default)
			)
			(layer "F.SilkS")
		)
		(fp_line
			(start 0.127 -0.5842)
			(end 0.127 0.5842)
			(stroke
				(width 0.1524)
				(type default)
			)
			(layer "F.SilkS")
		)
		(fp_line
			(start -0.127 -0.5842)
			(end -0.127 0.5842)
			(stroke
				(width 0.1524)
				(type default)
			)
			(layer "F.SilkS")
		)
		(fp_line
			(start 1.2954 0.635)
			(end -1.2954 0.635)
			(stroke
				(width 0.1524)
				(type default)
			)
			(layer "F.SilkS")
		)
		(fp_poly
			(pts
				(xy -0.9144 0.508) (xy -0.9144 0.3556) (xy -1.143 0.3556) (xy -1.143 -0.3556) (xy -0.9144 -0.3556)
				(xy -0.9144 -0.508) (xy 0.9144 -0.508) (xy 0.9144 -0.3556) (xy 1.143 -0.3556) (xy 1.143 0.3556)
				(xy 0.9144 0.3556) (xy 0.9144 0.508)
			)
			(stroke
				(width 0)
				(type default)
			)
			(fill no)
			(layer "F.CrtYd")
		)
		(pad "1" smd rect
			(at 0.7366 0 180)
			(size 0.7112 0.8128)
			(layers "F.Cu" "F.Mask" "F.Paste")
			(net "VCC5_CRTXX")
		)
		(pad "2" smd rect
			(at -0.7366 0 180)
			(size 0.7112 0.8128)
			(layers "F.Cu" "F.Mask" "F.Paste")
			(net "P5V_NODE1")
		)
	)
)
